(kicad_pcb
	(version 20260206)
	(generator "pcbnew")
	(generator_version "10.0")
	(general
		(thickness 1.6)
		(legacy_teardrops no)
	)
	(paper "A4")
	(title_block
		(title "03242023_DA0F0TMBIJ0_F0T_Motherboard_J_brd_V01_OCP.brd")
		(comment 1 "Grand Teton / footprints 2733-2738 of 6105")
	)
	(layers
		(0 "F.Cu" signal "TOP")
		(4 "In1.Cu" signal "GND")
		(6 "In2.Cu" signal "IN1")
		(8 "In3.Cu" signal "GND1")
		(10 "In4.Cu" signal "IN2")
		(12 "In5.Cu" signal "GND2")
		(14 "In6.Cu" signal "IN3")
		(16 "In7.Cu" signal "GND3")
		(18 "In8.Cu" signal "VCC")
		(20 "In9.Cu" signal "VCC1")
		(22 "In10.Cu" signal "GND4")
		(24 "In11.Cu" signal "IN4")
		(26 "In12.Cu" signal "GND5")
		(28 "In13.Cu" signal "IN5")
		(30 "In14.Cu" signal "GND6")
		(32 "In15.Cu" signal "IN6")
		(34 "In16.Cu" signal "GND7")
		(2 "B.Cu" signal "BOTTOM")
		(9 "F.Adhes" user "F.Adhesive")
		(11 "B.Adhes" user "B.Adhesive")
		(13 "F.Paste" user "Package Geometry/Pastemask Top")
		(15 "B.Paste" user "Package Geometry/Pastemask Bottom")
		(5 "F.SilkS" user "Ref Des/Silkscreen Top")
		(7 "B.SilkS" user "Ref Des/Silkscreen Bottom")
		(1 "F.Mask" user "Board Geometry/Soldermask Top")
		(3 "B.Mask" user "Board Geometry/Soldermask Bottom")
		(17 "Dwgs.User" user "User.Drawings")
		(19 "Cmts.User" user "User.Comments")
		(21 "Eco1.User" user "User.Eco1")
		(23 "Eco2.User" user "User.Eco2")
		(25 "Edge.Cuts" user "Board Geometry/Outline")
		(27 "Margin" user)
		(31 "F.CrtYd" user "Package Geometry/Place Bound Top")
		(29 "B.CrtYd" user "Package Geometry/Place Bound Bottom")
		(35 "F.Fab" user "Ref Des/Assembly Top")
		(33 "B.Fab" user "Ref Des/Assembly Bottom")
	)
	(footprint ""
		(layer "F.Cu")
		(at 361.953556 -338.180172 90)
		(property "Reference" "PR1769"
			(at 0 0 90)
			(layer "F.SilkS")
			(hide yes)
			(effects
				(font
					(size 1.27 1.27)
				)
			)
		)
		(property "Value" ""
			(at 0 0 90)
			(layer "F.Fab")
			(effects
				(font
					(size 1.27 1.27)
				)
			)
		)
		(duplicate_pad_numbers_are_jumpers no)
		(fp_line
			(start 0.7874 -0.4064)
			(end 0.7874 0.4064)
			(stroke
				(width 0.1524)
				(type default)
			)
			(layer "F.SilkS")
		)
		(fp_line
			(start -0.7874 -0.4064)
			(end 0.7874 -0.4064)
			(stroke
				(width 0.1524)
				(type default)
			)
			(layer "F.SilkS")
		)
		(fp_line
			(start 0.7874 0.4064)
			(end -0.7874 0.4064)
			(stroke
				(width 0.1524)
				(type default)
			)
			(layer "F.SilkS")
		)
		(fp_line
			(start -0.7874 0.4064)
			(end -0.7874 -0.4064)
			(stroke
				(width 0.1524)
				(type default)
			)
			(layer "F.SilkS")
		)
		(fp_line
			(start -0.12065 -0.305054)
			(end -0.12065 -0.2794)
			(stroke
				(width 0.1)
				(type default)
			)
			(layer "F.Fab")
		)
		(fp_line
			(start -0.67945 -0.305054)
			(end -0.12065 -0.305054)
			(stroke
				(width 0.1)
				(type default)
			)
			(layer "F.Fab")
		)
		(fp_line
			(start 0.67945 -0.3048)
			(end 0.67945 0.3048)
			(stroke
				(width 0.1)
				(type default)
			)
			(layer "F.Fab")
		)
		(fp_line
			(start 0.12065 -0.3048)
			(end 0.67945 -0.3048)
			(stroke
				(width 0.1)
				(type default)
			)
			(layer "F.Fab")
		)
		(fp_line
			(start 0.12065 -0.2794)
			(end 0.12065 -0.3048)
			(stroke
				(width 0.1)
				(type default)
			)
			(layer "F.Fab")
		)
		(fp_line
			(start -0.12065 -0.2794)
			(end 0.12065 -0.2794)
			(stroke
				(width 0.1)
				(type default)
			)
			(layer "F.Fab")
		)
		(fp_line
			(start 0.120396 0.2794)
			(end -0.12065 0.2794)
			(stroke
				(width 0.1)
				(type default)
			)
			(layer "F.Fab")
		)
		(fp_line
			(start -0.12065 0.2794)
			(end -0.12065 0.3048)
			(stroke
				(width 0.1)
				(type default)
			)
			(layer "F.Fab")
		)
		(fp_line
			(start 0.67945 0.3048)
			(end 0.120396 0.3048)
			(stroke
				(width 0.1)
				(type default)
			)
			(layer "F.Fab")
		)
		(fp_line
			(start 0.120396 0.3048)
			(end 0.120396 0.2794)
			(stroke
				(width 0.1)
				(type default)
			)
			(layer "F.Fab")
		)
		(fp_line
			(start -0.12065 0.3048)
			(end -0.67945 0.3048)
			(stroke
				(width 0.1)
				(type default)
			)
			(layer "F.Fab")
		)
		(fp_line
			(start -0.67945 0.3048)
			(end -0.67945 -0.305054)
			(stroke
				(width 0.1)
				(type default)
			)
			(layer "F.Fab")
		)
		(pad "1" smd circle
			(at -0.40005 0 90)
			(size 0 0)
			(layers "F.Cu" "F.Mask" "F.Paste")
			(net "SW_PVCCIN_CPU0_BOOT3")
		)
		(pad "2" smd circle
			(at 0.40005 0 90)
			(size 0 0)
			(layers "F.Cu" "F.Mask" "F.Paste")
			(net "SW_PVCCIN_CPU0_BOOT3_R")
		)
	)
	(footprint ""
		(layer "F.Cu")
		(at 299.02023 -52.368196 180)
		(property "Reference" "R2978"
			(at 0 0 180)
			(layer "F.SilkS")
			(hide yes)
			(effects
				(font
					(size 1.27 1.27)
				)
			)
		)
		(property "Value" ""
			(at 0 0 180)
			(layer "F.Fab")
			(effects
				(font
					(size 1.27 1.27)
				)
			)
		)
		(duplicate_pad_numbers_are_jumpers no)
		(fp_line
			(start 0.7874 0.4064)
			(end -0.7874 0.4064)
			(stroke
				(width 0.1524)
				(type default)
			)
			(layer "F.SilkS")
		)
		(fp_line
			(start 0.7874 -0.4064)
			(end 0.7874 0.4064)
			(stroke
				(width 0.1524)
				(type default)
			)
			(layer "F.SilkS")
		)
		(fp_line
			(start -0.7874 0.4064)
			(end -0.7874 -0.4064)
			(stroke
				(width 0.1524)
				(type default)
			)
			(layer "F.SilkS")
		)
		(fp_line
			(start -0.7874 -0.4064)
			(end 0.7874 -0.4064)
			(stroke
				(width 0.1524)
				(type default)
			)
			(layer "F.SilkS")
		)
		(fp_line
			(start 0.67945 0.3048)
			(end 0.120396 0.3048)
			(stroke
				(width 0.1)
				(type default)
			)
			(layer "F.Fab")
		)
		(fp_line
			(start 0.67945 -0.3048)
			(end 0.67945 0.3048)
			(stroke
				(width 0.1)
				(type default)
			)
			(layer "F.Fab")
		)
		(fp_line
			(start 0.12065 -0.2794)
			(end 0.12065 -0.3048)
			(stroke
				(width 0.1)
				(type default)
			)
			(layer "F.Fab")
		)
		(fp_line
			(start 0.12065 -0.3048)
			(end 0.67945 -0.3048)
			(stroke
				(width 0.1)
				(type default)
			)
			(layer "F.Fab")
		)
		(fp_line
			(start 0.120396 0.3048)
			(end 0.120396 0.2794)
			(stroke
				(width 0.1)
				(type default)
			)
			(layer "F.Fab")
		)
		(fp_line
			(start 0.120396 0.2794)
			(end -0.12065 0.2794)
			(stroke
				(width 0.1)
				(type default)
			)
			(layer "F.Fab")
		)
		(fp_line
			(start -0.12065 0.3048)
			(end -0.67945 0.3048)
			(stroke
				(width 0.1)
				(type default)
			)
			(layer "F.Fab")
		)
		(fp_line
			(start -0.12065 0.2794)
			(end -0.12065 0.3048)
			(stroke
				(width 0.1)
				(type default)
			)
			(layer "F.Fab")
		)
		(fp_line
			(start -0.12065 -0.2794)
			(end 0.12065 -0.2794)
			(stroke
				(width 0.1)
				(type default)
			)
			(layer "F.Fab")
		)
		(fp_line
			(start -0.12065 -0.305054)
			(end -0.12065 -0.2794)
			(stroke
				(width 0.1)
				(type default)
			)
			(layer "F.Fab")
		)
		(fp_line
			(start -0.67945 0.3048)
			(end -0.67945 -0.305054)
			(stroke
				(width 0.1)
				(type default)
			)
			(layer "F.Fab")
		)
		(fp_line
			(start -0.67945 -0.305054)
			(end -0.12065 -0.305054)
			(stroke
				(width 0.1)
				(type default)
			)
			(layer "F.Fab")
		)
		(pad "1" smd circle
			(at -0.40005 0 180)
			(size 0 0)
			(layers "F.Cu" "F.Mask" "F.Paste")
			(net "FAB_REV_ID0")
		)
		(pad "2" smd circle
			(at 0.40005 0 180)
			(size 0 0)
			(layers "F.Cu" "F.Mask" "F.Paste")
			(net "GND")
		)
	)
	(footprint ""
		(layer "F.Cu")
		(at 13.6398 -425.7548 90)
		(property "Reference" "R2696"
			(at 0 0 90)
			(layer "F.SilkS")
			(hide yes)
			(effects
				(font
					(size 1.27 1.27)
				)
			)
		)
		(property "Value" ""
			(at 0 0 90)
			(layer "F.Fab")
			(effects
				(font
					(size 1.27 1.27)
				)
			)
		)
		(duplicate_pad_numbers_are_jumpers no)
		(fp_line
			(start 0.7874 -0.4064)
			(end 0.7874 0.4064)
			(stroke
				(width 0.1524)
				(type default)
			)
			(layer "F.SilkS")
		)
		(fp_line
			(start -0.7874 -0.4064)
			(end 0.7874 -0.4064)
			(stroke
				(width 0.1524)
				(type default)
			)
			(layer "F.SilkS")
		)
		(fp_line
			(start 0.7874 0.4064)
			(end -0.7874 0.4064)
			(stroke
				(width 0.1524)
				(type default)
			)
			(layer "F.SilkS")
		)
		(fp_line
			(start -0.7874 0.4064)
			(end -0.7874 -0.4064)
			(stroke
				(width 0.1524)
				(type default)
			)
			(layer "F.SilkS")
		)
		(fp_line
			(start -0.12065 -0.305054)
			(end -0.12065 -0.2794)
			(stroke
				(width 0.1)
				(type default)
			)
			(layer "F.Fab")
		)
		(fp_line
			(start -0.67945 -0.305054)
			(end -0.12065 -0.305054)
			(stroke
				(width 0.1)
				(type default)
			)
			(layer "F.Fab")
		)
		(fp_line
			(start 0.67945 -0.3048)
			(end 0.67945 0.3048)
			(stroke
				(width 0.1)
				(type default)
			)
			(layer "F.Fab")
		)
		(fp_line
			(start 0.12065 -0.3048)
			(end 0.67945 -0.3048)
			(stroke
				(width 0.1)
				(type default)
			)
			(layer "F.Fab")
		)
		(fp_line
			(start 0.12065 -0.2794)
			(end 0.12065 -0.3048)
			(stroke
				(width 0.1)
				(type default)
			)
			(layer "F.Fab")
		)
		(fp_line
			(start -0.12065 -0.2794)
			(end 0.12065 -0.2794)
			(stroke
				(width 0.1)
				(type default)
			)
			(layer "F.Fab")
		)
		(fp_line
			(start 0.120396 0.2794)
			(end -0.12065 0.2794)
			(stroke
				(width 0.1)
				(type default)
			)
			(layer "F.Fab")
		)
		(fp_line
			(start -0.12065 0.2794)
			(end -0.12065 0.3048)
			(stroke
				(width 0.1)
				(type default)
			)
			(layer "F.Fab")
		)
		(fp_line
			(start 0.67945 0.3048)
			(end 0.120396 0.3048)
			(stroke
				(width 0.1)
				(type default)
			)
			(layer "F.Fab")
		)
		(fp_line
			(start 0.120396 0.3048)
			(end 0.120396 0.2794)
			(stroke
				(width 0.1)
				(type default)
			)
			(layer "F.Fab")
		)
		(fp_line
			(start -0.12065 0.3048)
			(end -0.67945 0.3048)
			(stroke
				(width 0.1)
				(type default)
			)
			(layer "F.Fab")
		)
		(fp_line
			(start -0.67945 0.3048)
			(end -0.67945 -0.305054)
			(stroke
				(width 0.1)
				(type default)
			)
			(layer "F.Fab")
		)
		(pad "1" smd circle
			(at -0.40005 0 90)
			(size 0 0)
			(layers "F.Cu" "F.Mask" "F.Paste")
			(net "TCA9539_0_ADD0")
		)
		(pad "2" smd circle
			(at 0.40005 0 90)
			(size 0 0)
			(layers "F.Cu" "F.Mask" "F.Paste")
			(net "GND")
		)
	)
	(footprint ""
		(layer "F.Cu")
		(at 332.68666 -16.2052 -90)
		(property "Reference" "R2132"
			(at 0 0 270)
			(layer "F.SilkS")
			(hide yes)
			(effects
				(font
					(size 1.27 1.27)
				)
			)
		)
		(property "Value" ""
			(at 0 0 270)
			(layer "F.Fab")
			(effects
				(font
					(size 1.27 1.27)
				)
			)
		)
		(duplicate_pad_numbers_are_jumpers no)
		(fp_line
			(start -0.7874 0.4064)
			(end -0.7874 -0.4064)
			(stroke
				(width 0.1524)
				(type default)
			)
			(layer "F.SilkS")
		)
		(fp_line
			(start 0.7874 0.4064)
			(end -0.7874 0.4064)
			(stroke
				(width 0.1524)
				(type default)
			)
			(layer "F.SilkS")
		)
		(fp_line
			(start -0.7874 -0.4064)
			(end 0.7874 -0.4064)
			(stroke
				(width 0.1524)
				(type default)
			)
			(layer "F.SilkS")
		)
		(fp_line
			(start 0.7874 -0.4064)
			(end 0.7874 0.4064)
			(stroke
				(width 0.1524)
				(type default)
			)
			(layer "F.SilkS")
		)
		(fp_line
			(start -0.67945 0.3048)
			(end -0.67945 -0.305054)
			(stroke
				(width 0.1)
				(type default)
			)
			(layer "F.Fab")
		)
		(fp_line
			(start -0.12065 0.3048)
			(end -0.67945 0.3048)
			(stroke
				(width 0.1)
				(type default)
			)
			(layer "F.Fab")
		)
		(fp_line
			(start 0.120396 0.3048)
			(end 0.120396 0.2794)
			(stroke
				(width 0.1)
				(type default)
			)
			(layer "F.Fab")
		)
		(fp_line
			(start 0.67945 0.3048)
			(end 0.120396 0.3048)
			(stroke
				(width 0.1)
				(type default)
			)
			(layer "F.Fab")
		)
		(fp_line
			(start -0.12065 0.2794)
			(end -0.12065 0.3048)
			(stroke
				(width 0.1)
				(type default)
			)
			(layer "F.Fab")
		)
		(fp_line
			(start 0.120396 0.2794)
			(end -0.12065 0.2794)
			(stroke
				(width 0.1)
				(type default)
			)
			(layer "F.Fab")
		)
		(fp_line
			(start -0.12065 -0.2794)
			(end 0.12065 -0.2794)
			(stroke
				(width 0.1)
				(type default)
			)
			(layer "F.Fab")
		)
		(fp_line
			(start 0.12065 -0.2794)
			(end 0.12065 -0.3048)
			(stroke
				(width 0.1)
				(type default)
			)
			(layer "F.Fab")
		)
		(fp_line
			(start 0.12065 -0.3048)
			(end 0.67945 -0.3048)
			(stroke
				(width 0.1)
				(type default)
			)
			(layer "F.Fab")
		)
		(fp_line
			(start 0.67945 -0.3048)
			(end 0.67945 0.3048)
			(stroke
				(width 0.1)
				(type default)
			)
			(layer "F.Fab")
		)
		(fp_line
			(start -0.67945 -0.305054)
			(end -0.12065 -0.305054)
			(stroke
				(width 0.1)
				(type default)
			)
			(layer "F.Fab")
		)
		(fp_line
			(start -0.12065 -0.305054)
			(end -0.12065 -0.2794)
			(stroke
				(width 0.1)
				(type default)
			)
			(layer "F.Fab")
		)
		(pad "1" smd circle
			(at -0.40005 0 270)
			(size 0 0)
			(layers "F.Cu" "F.Mask" "F.Paste")
			(net "JTAG_TRC_PCH_PTI<6>")
		)
		(pad "2" smd circle
			(at 0.40005 0 270)
			(size 0 0)
			(layers "F.Cu" "F.Mask" "F.Paste")
			(net "FM_ESPI_PLD_R1_EN")
		)
	)
	(footprint ""
		(layer "F.Cu")
		(at 304.53965 -60.094368)
		(property "Reference" "R2253"
			(at 0 0 0)
			(layer "F.SilkS")
			(hide yes)
			(effects
				(font
					(size 1.27 1.27)
				)
			)
		)
		(property "Value" ""
			(at 0 0 0)
			(layer "F.Fab")
			(effects
				(font
					(size 1.27 1.27)
				)
			)
		)
		(duplicate_pad_numbers_are_jumpers no)
		(fp_line
			(start -0.7874 -0.4064)
			(end 0.7874 -0.4064)
			(stroke
				(width 0.1524)
				(type default)
			)
			(layer "F.SilkS")
		)
		(fp_line
			(start -0.7874 0.4064)
			(end -0.7874 -0.4064)
			(stroke
				(width 0.1524)
				(type default)
			)
			(layer "F.SilkS")
		)
		(fp_line
			(start 0.7874 -0.4064)
			(end 0.7874 0.4064)
			(stroke
				(width 0.1524)
				(type default)
			)
			(layer "F.SilkS")
		)
		(fp_line
			(start 0.7874 0.4064)
			(end -0.7874 0.4064)
			(stroke
				(width 0.1524)
				(type default)
			)
			(layer "F.SilkS")
		)
		(fp_line
			(start -0.67945 -0.305054)
			(end -0.12065 -0.305054)
			(stroke
				(width 0.1)
				(type default)
			)
			(layer "F.Fab")
		)
		(fp_line
			(start -0.67945 0.3048)
			(end -0.67945 -0.305054)
			(stroke
				(width 0.1)
				(type default)
			)
			(layer "F.Fab")
		)
		(fp_line
			(start -0.12065 -0.305054)
			(end -0.12065 -0.2794)
			(stroke
				(width 0.1)
				(type default)
			)
			(layer "F.Fab")
		)
		(fp_line
			(start -0.12065 -0.2794)
			(end 0.12065 -0.2794)
			(stroke
				(width 0.1)
				(type default)
			)
			(layer "F.Fab")
		)
		(fp_line
			(start -0.12065 0.2794)
			(end -0.12065 0.3048)
			(stroke
				(width 0.1)
				(type default)
			)
			(layer "F.Fab")
		)
		(fp_line
			(start -0.12065 0.3048)
			(end -0.67945 0.3048)
			(stroke
				(width 0.1)
				(type default)
			)
			(layer "F.Fab")
		)
		(fp_line
			(start 0.120396 0.2794)
			(end -0.12065 0.2794)
			(stroke
				(width 0.1)
				(type default)
			)
			(layer "F.Fab")
		)
		(fp_line
			(start 0.120396 0.3048)
			(end 0.120396 0.2794)
			(stroke
				(width 0.1)
				(type default)
			)
			(layer "F.Fab")
		)
		(fp_line
			(start 0.12065 -0.3048)
			(end 0.67945 -0.3048)
			(stroke
				(width 0.1)
				(type default)
			)
			(layer "F.Fab")
		)
		(fp_line
			(start 0.12065 -0.2794)
			(end 0.12065 -0.3048)
			(stroke
				(width 0.1)
				(type default)
			)
			(layer "F.Fab")
		)
		(fp_line
			(start 0.67945 -0.3048)
			(end 0.67945 0.3048)
			(stroke
				(width 0.1)
				(type default)
			)
			(layer "F.Fab")
		)
		(fp_line
			(start 0.67945 0.3048)
			(end 0.120396 0.3048)
			(stroke
				(width 0.1)
				(type default)
			)
			(layer "F.Fab")
		)
		(pad "1" smd circle
			(at -0.40005 0)
			(size 0 0)
			(layers "F.Cu" "F.Mask" "F.Paste")
			(net "P3V3_AUX")
		)
		(pad "2" smd circle
			(at 0.40005 0)
			(size 0 0)
			(layers "F.Cu" "F.Mask" "F.Paste")
			(net "PECI_MUX_SEL_R")
		)
	)
	(footprint ""
		(layer "F.Cu")
		(at 264.126726 -129.439924 180)
		(property "Reference" "C2338"
			(at 0 0 180)
			(layer "F.SilkS")
			(hide yes)
			(effects
				(font
					(size 1.27 1.27)
				)
			)
		)
		(property "Value" ""
			(at 0 0 180)
			(layer "F.Fab")
			(effects
				(font
					(size 1.27 1.27)
				)
			)
		)
		(duplicate_pad_numbers_are_jumpers no)
		(fp_line
			(start 0.7874 0.4064)
			(end -0.7874 0.4064)
			(stroke
				(width 0.1524)
				(type default)
			)
			(layer "F.SilkS")
		)
		(fp_line
			(start 0.7874 -0.4064)
			(end 0.7874 0.4064)
			(stroke
				(width 0.1524)
				(type default)
			)
			(layer "F.SilkS")
		)
		(fp_line
			(start -0.7874 0.4064)
			(end -0.7874 -0.4064)
			(stroke
				(width 0.1524)
				(type default)
			)
			(layer "F.SilkS")
		)
		(fp_line
			(start -0.7874 -0.4064)
			(end 0.7874 -0.4064)
			(stroke
				(width 0.1524)
				(type default)
			)
			(layer "F.SilkS")
		)
		(fp_line
			(start 0.67945 0.3048)
			(end 0.120396 0.3048)
			(stroke
				(width 0.1)
				(type default)
			)
			(layer "F.Fab")
		)
		(fp_line
			(start 0.67945 -0.3048)
			(end 0.67945 0.3048)
			(stroke
				(width 0.1)
				(type default)
			)
			(layer "F.Fab")
		)
		(fp_line
			(start 0.12065 -0.2794)
			(end 0.12065 -0.3048)
			(stroke
				(width 0.1)
				(type default)
			)
			(layer "F.Fab")
		)
		(fp_line
			(start 0.12065 -0.3048)
			(end 0.67945 -0.3048)
			(stroke
				(width 0.1)
				(type default)
			)
			(layer "F.Fab")
		)
		(fp_line
			(start 0.120396 0.3048)
			(end 0.120396 0.2794)
			(stroke
				(width 0.1)
				(type default)
			)
			(layer "F.Fab")
		)
		(fp_line
			(start 0.120396 0.2794)
			(end -0.12065 0.2794)
			(stroke
				(width 0.1)
				(type default)
			)
			(layer "F.Fab")
		)
		(fp_line
			(start -0.12065 0.3048)
			(end -0.67945 0.3048)
			(stroke
				(width 0.1)
				(type default)
			)
			(layer "F.Fab")
		)
		(fp_line
			(start -0.12065 0.2794)
			(end -0.12065 0.3048)
			(stroke
				(width 0.1)
				(type default)
			)
			(layer "F.Fab")
		)
		(fp_line
			(start -0.12065 -0.2794)
			(end 0.12065 -0.2794)
			(stroke
				(width 0.1)
				(type default)
			)
			(layer "F.Fab")
		)
		(fp_line
			(start -0.12065 -0.305054)
			(end -0.12065 -0.2794)
			(stroke
				(width 0.1)
				(type default)
			)
			(layer "F.Fab")
		)
		(fp_line
			(start -0.67945 0.3048)
			(end -0.67945 -0.305054)
			(stroke
				(width 0.1)
				(type default)
			)
			(layer "F.Fab")
		)
		(fp_line
			(start -0.67945 -0.305054)
			(end -0.12065 -0.305054)
			(stroke
				(width 0.1)
				(type default)
			)
			(layer "F.Fab")
		)
		(pad "1" smd circle
			(at -0.40005 0 180)
			(size 0 0)
			(layers "F.Cu" "F.Mask" "F.Paste")
			(net "P3V3")
		)
		(pad "2" smd circle
			(at 0.40005 0 180)
			(size 0 0)
			(layers "F.Cu" "F.Mask" "F.Paste")
			(net "GND")
		)
	)
)
